FILE_TYPE = MULTI_PHYS_TABLE;

PART 'Q_RES_4P_12'

{========================================================================================}
:VALUE    | TOLERANCE | WATTAGE | PART_TYPE | MATERIAL | PART_NUMBER        = STANDARD        | LIFECYCLE      | PART_NUMBER   | JEDEC_TYPE           | DESCRIPTION                                   | MANUFTR | MANUF_PN            | RD_CMPLS_LVL | CMPLS_LVL | CLASS      | DIP_SMD | FROM_PJ        | DATA                          | FP_ECN                     | EE_CHECK_LIST  | PSL | PREFERENCE | CREATOR | STATUS | CREATEDAY  ;
{========================================================================================}
 '0.002'  | '1%'      | '2W'    | 'SMLF'    | 'CHIP'   | 'CS+002AFR00'(!)   = ''              | ''             | 'CS+002AFR00' |'R2512_4P'| 'RES CHIP 0.002 2W +-1%(2512)'                | 'WTC'   | 'WW25NR002FTL'      | ''           | 'EP_Tmp'  | 'DISCRETE' | ''      | 'T96-JAMES'    | 'WTC_WW25N_R2512_4P.pdf'      | ''                         | 'R2512_4P.xls' | ''  | ''         | ''      | ''     | '20111219'
 '0.002'  | '1%'      | '2W'    | 'SMLF'    | 'EMPTY'  | 'CS+002AFR00'(!)   = ''              | ''             | 'CS+002AFR00' |'R2512_4P'| 'RES CHIP 0.002 2W +-1%(2512)'                | 'WTC'   | 'WW25NR002FTL'      | ''           | 'EP_Tmp'  | 'DISCRETE' | ''      | 'T96-JAMES'    | 'WTC_WW25N_R2512_4P.pdf'      | ''                         | 'R2512_4P.xls' | ''  | ''         | ''      | ''     | '20111219'
 '0.001'  | '1%'      | '3W'    | 'SMLF'    | 'CHIP'   | 'CS0000DFR01'(!)   = 'Potential'     | 'End of Life'  | 'CS0000DFR01' |'R2512_4P_EOL'| 'RES CHIP 0.001 3W +-1%(2512)'                | 'RLC'   | 'LR25-23R001FE6'    | ''           | 'EP(V1)'  | 'DISCRETE' | ''      | 'JB9-PETER'    | 'RLC_LR SERIES.pdf'           | ''                         | ''             | ''  | ''         | ''      | ''     | '20111223'
 '0.001'  | '1%'      | '3W'    | 'SMLF'    | 'EMPTY'  | 'CS0000DFR01'(!)   = 'Potential'     | 'End of Life'  | 'CS0000DFR01' |'R2512_4P_EOL'| 'RES CHIP 0.001 3W +-1%(2512)'                | 'RLC'   | 'LR25-23R001FE6'    | ''           | 'EP(V1)'  | 'DISCRETE' | ''      | 'JB9-PETER'    | 'RLC_LR SERIES.pdf'           | ''                         | ''             | ''  | ''         | ''      | ''     | '20111223'
 '0.020'  | '1%'      | '2W'    | 'SMLF'    | 'CHIP'   | 'CS+020AFR00'(!)   = ''              | ''             | 'CS+020AFR00' |'R2512_4P'| 'RES CHIP 0.020 2W +-1%(2512)'                | 'TAI'   | 'RLP25FEER020'      | ''           | 'EP_Tmp'  | 'DISCRETE' | ''      | 'JB9-PETER'    | ''                            | ''                         | ''             | ''  | ''         | ''      | ''     | '20111229'
 '0.020'  | '1%'      | '2W'    | 'SMLF'    | 'EMPTY'  | 'CS+020AFR00'(!)   = ''              | ''             | 'CS+020AFR00' |'R2512_4P'| 'RES CHIP 0.020 2W +-1%(2512)'                | 'TAI'   | 'RLP25FEER020'      | ''           | 'EP_Tmp'  | 'DISCRETE' | ''      | 'JB9-PETER'    | ''                            | ''                         | ''             | ''  | ''         | ''      | ''     | '20111229'
 '0.001'  | '1%'      | '2W'    | 'SMLF'    | 'CHIP'   | 'CS+001AF104'(!)   = ''              | 'End of Life'  | 'CS+001AF104' |'R2512_4P_EOL'| 'RES CHIP 0.001 2W(+-1%.2512) L-F'            | 'ROH'   | 'PMR100HZP4FV1L00'  | 'LF'         | 'EP'      | 'DISCRETE' | ''      | 'JB9-LINHAN'   | ''                            | ''                         | 'R2512_4P.xls' | ''  | ''         | ''      | ''     | '20120403'
 '0.001'  | '1%'      | '2W'    | 'SMLF'    | 'EMPTY'  | 'CS+001AF104'(!)   = ''              | 'End of Life'  | 'CS+001AF104' |'R2512_4P_EOL'| 'RES CHIP 0.001 2W(+-1%.2512) L-F'            | 'ROH'   | 'PMR100HZP4FV1L00'  | 'LF'         | 'EP'      | 'DISCRETE' | ''      | 'JB9-LINHAN'   | ''                            | ''                         | 'R2512_4P.xls' | ''  | ''         | ''      | ''     | '20120403'
 '0.0005' | '1%'      | '2W'    | 'SMLF'    | 'CHIP'   | 'CS0000AFR00'(!)   = ''              | ''             | 'CS0000AFR00' |'R2512_4P'| 'RES CHIP 0.0005 2W +-1%(2512)'               | 'TAI'   | 'RLM25FEEMR0005'    | 'EP(V1)'     | ''        | 'DISCRETE' | ''      | 'JBA-LINHAN'   | 'TAI_RLM25FEEMR0005.pdf'      | ''                         | 'R2512_4P.xls' | ''  | ''         | ''      | ''     | '20120724'
 '0.0005' | '1%'      | '2W'    | 'SMLF'    | 'EMPTY'  | 'CS0000AFR00'(!)   = ''              | ''             | 'CS0000AFR00' |'R2512_4P'| 'RES CHIP 0.0005 2W +-1%(2512)'               | 'TAI'   | 'RLM25FEEMR0005'    | 'EP(V1)'     | ''        | 'DISCRETE' | ''      | 'JBA-LINHAN'   | 'TAI_RLM25FEEMR0005.pdf'      | ''                         | 'R2512_4P.xls' | ''  | ''         | ''      | ''     | '20120724'
 '0.0002' | '1%'      | '4W'    | 'SMLF'    | 'CHIP'   | 'CS0000FFT01'(!)   = ''              | ''             | 'CS0000FFT01' |'R2725_4PXA'| 'RES CHIP 0.0002 4W +-1%(2725)H1.131_PIN CUT' | 'RLC'   | 'LR2725-24R0002F1'  | 'EP(V1)'     | ''        | 'DISCRETE' | ''      | 'TU1H-LIN-HAN' | 'LR-SERIES_REV2013-04-03.pdf' | 'R2725_4P.msg'             | ''             | ''  | ''         | ''      | ''     | '20131213'
 '0.0002' | '1%'      | '4W'    | 'SMLF'    | 'EMPTY'  | 'CS0000FFT01'(!)   = ''              | ''             | 'CS0000FFT01' |'R2725_4PXA'| 'RES CHIP 0.0002 4W +-1%(2725)H1.131_PIN CUT' | 'RLC'   | 'LR2725-24R0002F1'  | 'EP(V1)'     | ''        | 'DISCRETE' | ''      | 'TU1H-LIN-HAN' | 'LR-SERIES_REV2013-04-03.pdf' | 'R2725_4P.msg'             | ''             | ''  | ''         | ''      | ''     | '20131213'
 '0.001'  | '1%'      | '3W'    | 'SMLF'    | 'CHIP'   | 'SP_CS+001DFR00'(!) = ''              | ''             | 'CS+001DFR00' |'R2512_4P_H41'| 'RES CHIP 0.001 3W(+-1%,2512)_4P'             | 'RLC'   | 'LR2512-23R001F4'   | 'EP(V1)'     | 'EP(V1)'  | 'DISCRETE' | ''      | 'UH3M-CARLOS'  | 'RLC_LR2512-23R001F4.pdf'     | 'LR2512-23R001F4_UH3M.msg' | ''             | ''  | ''         | ''      | ''     | '20160303'
 '0.001'  | '1%'      | '3W'    | 'SMLF'    | 'EMPTY'  | 'SP_CS+001DFR00'(!) = ''              | ''             | 'CS+001DFR00' |'R2512_4P_H41'| 'RES CHIP 0.001 3W(+-1%,2512)_4P'             | 'RLC'   | 'LR2512-23R001F4'   | 'EP(V1)'     | 'EP(V1)'  | 'DISCRETE' | ''      | 'UH3M-CARLOS'  | 'RLC_LR2512-23R001F4.pdf'     | 'LR2512-23R001F4_UH3M.msg' | ''             | ''  | ''         | ''      | ''     | '20160303'
 '0.0022' | '1%'      | '2W'    | 'SMLF'    | 'CHIP'   | 'SP_CS+002AFR02_2'(!) = ''              | 'End of Life'  | 'CS+002AFR02' |'R2512_4P_EOL'| 'RES CHIP 0.0022 2W +-1%(2512)'               | 'CYN'   | 'RL3264-9V-2R2M-FN' | 'EP(V1)'     | ''        | 'DISCRETE' | ''      | 'T2N-MORRIS'   | 'CYN_RL3264-9V-2R2M-FN.pdf'   | 'R2512A&4P&R2512_4PXF.doc' | ''             | ''  | ''         | ''      | ''     | '20170906'
 '0.0022' | '1%'      | '2W'    | 'SMLF'    | 'EMPTY'  | 'SP_CS+002AFR02_2'(!) = ''              | 'End of Life'  | 'CS+002AFR02' |'R2512_4P_EOL'| 'RES CHIP 0.0022 2W +-1%(2512)'               | 'CYN'   | 'RL3264-9V-2R2M-FN' | 'EP(V1)'     | ''        | 'DISCRETE' | ''      | 'T2N-MORRIS'   | 'CYN_RL3264-9V-2R2M-FN.pdf'   | 'R2512A&4P&R2512_4PXF.doc' | ''             | ''  | ''         | ''      | ''     | '20170906'
 '0.0003' | '1%'      | '8W'    | 'SMLF'    | 'CHIP'   | 'SP_CS0000LFR00_1'(!) = ''              | ''             | 'CS0000LFR00' |'R2512_4P_H58_SHORT'| 'RES CHIP 0.0003 8W +-1% (2512)KOA'           | 'KOA'   | 'PSL2NTEBL300F'     | 'EP(V1)'     | ''        | 'DISCRETE' | ''      | 'S8A-DAVID'    | 'KOA_PSL2NTEBL300F.pdf'       | 'PSL2NTEBL300F.msg'        | ''             | ''  | ''         | ''      | ''     | '20200429'
 '0.0003' | '1%'      | '8W'    | 'SMLF'    | 'EMPTY'  | 'SP_CS0000LFR00_1'(!) = ''              | ''             | 'CS0000LFR00' |'R2512_4P_H58_SHORT'| 'RES CHIP 0.0003 8W +-1% (2512)KOA'           | 'KOA'   | 'PSL2NTEBL300F'     | 'EP(V1)'     | ''        | 'DISCRETE' | ''      | 'S8A-DAVID'    | 'KOA_PSL2NTEBL300F.pdf'       | 'PSL2NTEBL300F.msg'        | ''             | ''  | ''         | ''      | ''     | '20200429'
 '0.003'  | '1%'      | '2W'    | 'SMLF'    | 'CHIP'   | 'SP_CS+003AFR00_3'(!) = ''              | ''             | 'CS+003AFR00' |'R2512_4P'| 'RES CHIP 0.003 2W +-1%(2512)'                | 'YGO'   | 'PR2512FKF7W0R003L' | 'EP(V1)'     | 'EP(V1)'  | 'DISCRETE' | ''      | 'S8Z-JW'       | 'YGO_PR2512FKF7W0R003L.pdf'   | 'SP_CS+003AFR00_3.msg'     | ''             | ''  | ''         | ''      | ''     | '20200709'
 '0.003'  | '1%'      | '2W'    | 'SMLF'    | 'EMPTY'  | 'SP_CS+003AFR00_3'(!) = ''              | ''             | 'CS+003AFR00' |'R2512_4P'| 'RES CHIP 0.003 2W +-1%(2512)'                | 'YGO'   | 'PR2512FKF7W0R003L' | 'EP(V1)'     | 'EP(V1)'  | 'DISCRETE' | ''      | 'S8Z-JW'       | 'YGO_PR2512FKF7W0R003L.pdf'   | 'SP_CS+003AFR00_3.msg'     | ''             | ''  | ''         | ''      | ''     | '20200709'
 '0.001'  | '0.5%'    | '1W'    | 'SMLF'    | 'CHIP'   | 'CS+0018DR01'(!)   = 'End of Design' | 'Comp-Approve' | 'CS+0018DR01' |'R2512_4PXI'| 'RES CHIP 0.001 1W +-0.5%(2512)C-S'           | 'DAL'   | 'WSK25121L000DEA'   | 'EP(V1)'     | 'EP(V1)'  | 'DISCRETE' | ''      | 'T2M-CHRIS'    | 'DAL_WSK25121L000DEA.pdf'     | ''                         | ''             | ''  | ''         | ''      | ''     | '20201225'
 '0.001'  | '0.5%'    | '1W'    | 'SMLF'    | 'EMPTY'  | 'CS+0018DR01'(!)   = 'End of Design' | 'Comp-Approve' | 'CS+0018DR01' |'R2512_4PXI'| 'RES CHIP 0.001 1W +-0.5%(2512)C-S'           | 'DAL'   | 'WSK25121L000DEA'   | 'EP(V1)'     | 'EP(V1)'  | 'DISCRETE' | ''      | 'T2M-CHRIS'    | 'DAL_WSK25121L000DEA.pdf'     | ''                         | ''             | ''  | ''         | ''      | ''     | '20201225'
 '0.002'  | '0.5%'    | '1W'    | 'SMLF'    | 'CHIP'   | 'CS+0028DR01'(!)   = 'End of Design' | 'Comp-Approve' | 'CS+0028DR01' |'R2512_4PXI'| 'RES CHIP 0.002 1W +-0.5%(2512)C-S'           | 'DAL'   | 'WSK25122L000DEA'   | 'EP(V1)'     | 'EP(V1)'  | 'DISCRETE' | ''      | 'T2M-CHRIS'    | 'DAL_WSK25122L000DEA.pdf'     | ''                         | ''             | ''  | ''         | ''      | ''     | '20201225'
 '0.002'  | '0.5%'    | '1W'    | 'SMLF'    | 'EMPTY'  | 'CS+0028DR01'(!)   = 'End of Design' | 'Comp-Approve' | 'CS+0028DR01' |'R2512_4PXI'| 'RES CHIP 0.002 1W +-0.5%(2512)C-S'           | 'DAL'   | 'WSK25122L000DEA'   | 'EP(V1)'     | 'EP(V1)'  | 'DISCRETE' | ''      | 'T2M-CHRIS'    | 'DAL_WSK25122L000DEA.pdf'     | ''                         | ''             | ''  | ''         | ''      | ''     | '20201225'
 '0.0005' | '1%'      | '3W'    | 'SMLF'    | 'CHIP'   | 'SP_CS0000DFR18'(!) = ''              | ''             | 'CS0000DFR18' |'R2512_4P_H41'| 'RES CHIP 0.0005 3W +-1%(2512)RLC_4P'         | 'RLC'   | 'LR2512-23R0005F4'  | 'EP(V1)'     | 'EP(V1)'  | 'DISCRETE' | ''      | 'S8Z-BRIAN'    | 'RLC_LR2512-23R0005F4.pdf'    | 'LR2512-23R0005F4.msg'     | ''             | ''  | ''         | ''      | ''     | '20210428'
 '0.0005' | '1%'      | '3W'    | 'SMLF'    | 'EMPTY'  | 'SP_CS0000DFR18'(!) = ''              | ''             | 'CS0000DFR18' |'R2512_4P_H41'| 'RES CHIP 0.0005 3W +-1%(2512)RLC_4P'         | 'RLC'   | 'LR2512-23R0005F4'  | 'EP(V1)'     | 'EP(V1)'  | 'DISCRETE' | ''      | 'S8Z-BRIAN'    | 'RLC_LR2512-23R0005F4.pdf'    | 'LR2512-23R0005F4.msg'     | ''             | ''  | ''         | ''      | ''     | '20210428'
 '0.001'  | '1%'      | '3W'    | 'SMLF'    | 'CHIP'   | 'SP_CS+001DFR10'(!) = ''              | ''             | 'CS+001DFR10' |'R2512_4P_H41'| 'RES CHIP 0.001 3W +-1%(2512)RLC_4P'          | 'RLC'   | 'LR2512-23R001F4'   | 'EP(V1)'     | 'EP(V1)'  | 'DISCRETE' | ''      | 'S8Z-BRIAN'    | 'RLC_LR2512-23R001F4.pdf'     | 'LR2512-23R001F4.msg'      | ''             | ''  | ''         | ''      | ''     | '20210428'
 '0.001'  | '1%'      | '3W'    | 'SMLF'    | 'EMPTY'  | 'SP_CS+001DFR10'(!) = ''              | ''             | 'CS+001DFR10' |'R2512_4P_H41'| 'RES CHIP 0.001 3W +-1%(2512)RLC_4P'          | 'RLC'   | 'LR2512-23R001F4'   | 'EP(V1)'     | 'EP(V1)'  | 'DISCRETE' | ''      | 'S8Z-BRIAN'    | 'RLC_LR2512-23R001F4.pdf'     | 'LR2512-23R001F4.msg'      | ''             | ''  | ''         | ''      | ''     | '20210428'
 '0.003'  | '1%'      | '3W'    | 'SMLF'    | 'CHIP'   | 'SP_CS+003DFR03_1'(!) = ''               | ''               | 'CS+003DFR03' |'R2512_4P_H41'| 'RES CHIP 0.003 3W +-1%(2512)RLC_4P'          | 'RLC'   | 'LR2512-23R003F4'   | 'EP(V1)'     | 'EP(V1)'  | 'DISCRETE' | ''      | 'MFZ-FRANK'    | 'RLC_LR2512-23R003F4.pdf'     | 'SP_CS+003DFR03.msg'       | ''             | ''  | ''         | ''      | ''     | '20220421'
 '0.003'  | '1%'      | '3W'    | 'SMLF'    | 'EMPTY'  | 'SP_CS+003DFR03_1'(!) = ''               | ''               | 'CS+003DFR03' |'R2512_4P_H41'| 'RES CHIP 0.003 3W +-1%(2512)RLC_4P'          | 'RLC'   | 'LR2512-23R003F4'   | 'EP(V1)'     | 'EP(V1)'  | 'DISCRETE' | ''      | 'MFZ-FRANK'    | 'RLC_LR2512-23R003F4.pdf'     | 'SP_CS+003DFR03.msg'       | ''             | ''  | ''         | ''      | ''     | '20220421'

END_PART

END.

